FILE_TYPE = CONNECTIVITY;
{Allegro Design Entry HDL 17.2-2016 S081 (4005846) 1/11/2022}
"PAGE_NUMBER" = 149;
0"NC";
1"GND\g";
2"GND\g";
3"P3E_PCH_NVS_RX_DN<1>";
4"P3E_PCH_NVS_RX_DP<1>";
5"P3E_PCH_NVS_RX_DP<0>";
6"RST_PERST_0_SWB_BUF_N";
7"P3E_PCH_NVS_TX_C_DN<0>";
8"P3E_PCH_NVS_TX_C_DP<0>";
9"PRSNT_SWB_N";
10"P5E_CPU1_PE0_RX_DP<9>";
11"P5E_CPU1_PE4_RX_DN<6>";
12"P5E_CPU1_PE0_RX_DN<9>";
13"P3E_PCH_NVS_TX_C_DN<1>";
14"P3E_PCH_NVS_TX_C_DP<1>";
15"P5E_CPU1_PE0_RX_DN<10>";
16"P5E_CPU1_PE0_RX_DP<10>";
17"P5E_CPU1_PE4_RX_DP<5>";
18"P5E_CPU1_PE4_RX_DN<5>";
19"P5E_CPU1_PE4_TX_C_DP<5>";
20"P2E_MB_BMC_RX_DN<0>";
21"P2E_MB_BMC_RX_DP<0>";
22"P2E_MB_BMC_TX_BUF_C_DN<0>";
23"P2E_MB_BMC_TX_BUF_C_DP<0>";
24"GPU_FPGA_THERM_OVERT_N";
25"RST_PERST_1_SWB_BUF_N";
26"P5E_CPU1_PE0_RX_DN<11>";
27"P5E_CPU1_PE4_RX_DN<4>";
28"P5E_CPU1_PE4_RX_DP<4>";
29"P5E_CPU1_PE0_TX_C_DN<11>";
30"P5E_CPU1_PE0_TX_C_DN<9>";
31"P5E_CPU1_PE4_TX_C_DP<7>";
32"P5E_CPU1_PE4_TX_C_DN<7>";
33"P5E_CPU1_PE0_TX_C_DN<8>";
34"P5E_CPU1_PE4_RX_DN<7>";
35"P5E_CPU1_PE0_RX_DP<8>";
36"P5E_CPU1_PE0_RX_DN<8>";
37"P5E_CPU1_PE4_RX_DP<7>";
38"P5E_CPU1_PE0_TX_C_DP<8>";
39"P3E_PCH_NVS_RX_DN<0>";
40"HGX_DETECT_N_ISO";
41"P5E_CPU1_PE0_RX_DN<13>";
42"SMB_1_BMC_GPU_BUF_SDA";
43"SMB_1_BMC_GPU_BUF_SCL";
44"GPU_NVS_PWR_BRAKE_N_BUF";
45"P5E_CPU1_PE4_TX_C_DP<3>";
46"CLK_100M_GPU_1_DP";
47"CLK_100M_GPU_1_DN";
48"P5E_CPU1_PE0_RX_DP<13>";
49"P5E_CPU1_PE4_RX_DN<2>";
50"P5E_CPU1_PE4_RX_DP<2>";
51"P5E_CPU1_PE0_TX_C_DP<13>";
52"P5E_CPU1_PE4_TX_C_DN<2>";
53"P5E_CPU1_PE4_TX_C_DP<2>";
54"CLK_100M_SWB_DN";
55"CLK_100M_SWB_DP";
56"SMB_2_BMC_GPU_BUF_SCL";
57"SMB_2_BMC_GPU_BUF_SDA";
58"P5E_CPU1_PE0_RX_DN<14>";
59"P5E_CPU1_PE0_RX_DP<14>";
60"P5E_CPU1_PE4_RX_DP<1>";
61"P5E_CPU1_PE0_TX_C_DP<14>";
62"P5E_CPU1_PE4_TX_C_DN<1>";
63"NC_J112_N2";
64"NC_J112_O2";
65"CLK_100M_GPU_FPGA_DN";
66"GPU_FPGA_READY";
67"RST_PERST_2_SWB_BUF_N";
68"P5E_CPU1_PE0_RX_DP<15>";
69"P5E_CPU1_PE4_RX_DN<0>";
70"USB2_HUB_BUF_SWB_DP";
71"CLK_100M_GPU_2_DP";
72"CLK_100M_GPU_2_DN";
73"P5E_CPU1_PE4_TX_C_DP<0>";
74"P5E_CPU1_PE4_TX_C_DN<0>";
75"P5E_CPU1_PE0_TX_C_DP<15>";
76"P5E_CPU1_PE0_TX_C_DN<15>";
77"P5E_CPU1_PE4_RX_DP<0>";
78"P5E_CPU1_PE4_TX_C_DN<5>";
79"P5E_CPU1_PE0_TX_C_DP<10>";
80"P5E_CPU1_PE4_TX_C_DN<6>";
81"P5E_CPU1_PE4_RX_DP<6>";
82"P5E_CPU1_PE0_TX_C_DP<9>";
83"P5E_CPU1_PE4_TX_C_DP<6>";
84"P5E_CPU1_PE0_RX_DP<12>";
85"CLK_100M_GPU_FPGA_DP";
86"P5E_CPU1_PE4_TX_C_DN<4>";
87"NC_J112_P5";
88"NC_J112_R5";
89"NC_J112_S5";
90"NC_J112_O5";
91"P5E_CPU1_PE4_TX_C_DP<4>";
92"P5E_CPU1_PE0_TX_C_DN<13>";
93"P5E_CPU1_PE4_RX_DN<1>";
94"P5E_CPU1_PE0_TX_C_DN<14>";
95"P5E_CPU1_PE4_TX_C_DP<1>";
96"P5E_CPU1_PE0_TX_C_DP<12>";
97"P5E_CPU1_PE0_TX_C_DN<10>";
98"P5E_CPU1_PE0_RX_DP<11>";
99"P5E_CPU1_PE0_TX_C_DP<11>";
100"USB2_HUB_BUF_SWB_DN";
101"P5E_CPU1_PE0_RX_DN<12>";
102"P5E_CPU1_PE4_TX_C_DN<3>";
103"P5E_CPU1_PE0_TX_C_DN<12>";
104"P5E_CPU1_PE4_RX_DN<3>";
105"P5E_CPU1_PE4_RX_DP<3>";
106"P5E_CPU1_PE0_RX_DN<15>";
%"CONN160_10131762101LF"
"1","(600,1675)","0","pure_quanta","I75";
;
PART_NUMBER"DFHSG0FR007"
MATERIAL"IO"
PART_TYPE"THLF"
LOCATION"J112"
CDS_LIB"pure_quanta"
CDS_LMAN_SYM_OUTLINE"-1075,2225,1075,-2225"
NEEDS_NO_SIZE"TRUE"
VALUE"CONN160_10131762-101LF"
$SEC"1"
CDS_SEC"1";
"T8"
$PN"T8"6;
"S8"
$PN"S8"1;
"R8"
$PN"R8"8;
"Q8"
$PN"Q8"7;
"P8"
$PN"P8"1;
"O8"
$PN"O8"5;
"T7"
$PN"T7"1;
"S7"
$PN"S7"14;
"R7"
$PN"R7"13;
"Q7"
$PN"Q7"1;
"P7"
$PN"P7"4;
"O7"
$PN"O7"3;
"T6"
$PN"T6"24;
"S6"
$PN"S6"1;
"R6"
$PN"R6"23;
"Q6"
$PN"Q6"22;
"P6"
$PN"P6"1;
"O6"
$PN"O6"21;
"T5"
$PN"T5"1;
"S5"
$PN"S5"89;
"R5"
$PN"R5"88;
"Q5"
$PN"Q5"1;
"P5"
$PN"P5"87;
"O5"
$PN"O5"90;
"N8"
$PN"N8"39;
"M8"
$PN"M8"1;
"N7"
$PN"N7"1;
"M7"
$PN"M7"83;
"N6"
$PN"N6"20;
"M6"
$PN"M6"1;
"N5"
$PN"N5"1;
"M5"
$PN"M5"91;
"L5"
$PN"L5"86;
"L6"
$PN"L6"19;
"L7"
$PN"L7"80;
"L8"
$PN"L8"31;
"K5"
$PN"K5"1;
"K6"
$PN"K6"78;
"K7"
$PN"K7"1;
"K8"
$PN"K8"32;
"J5"
$PN"J5"99;
"J6"
$PN"J6"1;
"J7"
$PN"J7"82;
"J8"
$PN"J8"1;
"I5"
$PN"I5"29;
"I6"
$PN"I6"79;
"I7"
$PN"I7"30;
"I8"
$PN"I8"38;
"H5"
$PN"H5"1;
"H6"
$PN"H6"97;
"H7"
$PN"H7"1;
"H8"
$PN"H8"33;
"G5"
$PN"G5"28;
"G6"
$PN"G6"1;
"G7"
$PN"G7"81;
"G8"
$PN"G8"1;
"F5"
$PN"F5"27;
"F6"
$PN"F6"18;
"F7"
$PN"F7"11;
"F8"
$PN"F8"34;
"E5"
$PN"E5"1;
"E6"
$PN"E6"17;
"E7"
$PN"E7"1;
"E8"
$PN"E8"37;
"D5"
$PN"D5"26;
"D6"
$PN"D6"1;
"D7"
$PN"D7"10;
"D8"
$PN"D8"1;
"C5"
$PN"C5"98;
"C6"
$PN"C6"16;
"C7"
$PN"C7"12;
"C8"
$PN"C8"35;
"B5"
$PN"B5"1;
"B6"
$PN"B6"15;
"B7"
$PN"B7"1;
"B8"
$PN"B8"36;
"A5"
$PN"A5"25;
"A6"
$PN"A6"1;
"A7"
$PN"A7"9;
"A8"
$PN"A8"1;
%"CONN160_10131762101LF"
"2","(5150,1750)","0","pure_quanta","I76";
;
PART_NUMBER"DFHSG0FR007"
MATERIAL"IO"
PART_TYPE"THLF"
LOCATION"J112"
CDS_LIB"pure_quanta"
CDS_LMAN_SYM_OUTLINE"-1075,2225,1075,-2225"
NEEDS_NO_SIZE"TRUE"
VALUE"CONN160_10131762-101LF"
$SEC"2"
CDS_SEC"2";
"T4"
$PN"T4"44;
"S4"
$PN"S4"2;
"R4"
$PN"R4"42;
"Q4"
$PN"Q4"43;
"P4"
$PN"P4"2;
"O4"
$PN"O4"46;
"T3"
$PN"T3"2;
"S3"
$PN"S3"57;
"R3"
$PN"R3"56;
"Q3"
$PN"Q3"2;
"P3"
$PN"P3"55;
"O3"
$PN"O3"54;
"T2"
$PN"T2"66;
"S2"
$PN"S2"2;
"R2"
$PN"R2"85;
"Q2"
$PN"Q2"65;
"P2"
$PN"P2"2;
"O2"
$PN"O2"64;
"T1"
$PN"T1"2;
"S1"
$PN"S1"70;
"R1"
$PN"R1"100;
"Q1"
$PN"Q1"2;
"P1"
$PN"P1"71;
"O1"
$PN"O1"72;
"N4"
$PN"N4"47;
"M4"
$PN"M4"2;
"N3"
$PN"N3"2;
"M3"
$PN"M3"53;
"N2"
$PN"N2"63;
"M2"
$PN"M2"2;
"N1"
$PN"N1"2;
"M1"
$PN"M1"73;
"L1"
$PN"L1"74;
"L2"
$PN"L2"62;
"L3"
$PN"L3"52;
"L4"
$PN"L4"45;
"K1"
$PN"K1"2;
"K2"
$PN"K2"95;
"K3"
$PN"K3"2;
"K4"
$PN"K4"102;
"J1"
$PN"J1"75;
"J2"
$PN"J2"2;
"J3"
$PN"J3"51;
"J4"
$PN"J4"2;
"I1"
$PN"I1"76;
"I2"
$PN"I2"61;
"I3"
$PN"I3"92;
"I4"
$PN"I4"96;
"H1"
$PN"H1"2;
"H2"
$PN"H2"94;
"H3"
$PN"H3"2;
"H4"
$PN"H4"103;
"G1"
$PN"G1"77;
"G2"
$PN"G2"2;
"G3"
$PN"G3"50;
"G4"
$PN"G4"2;
"F1"
$PN"F1"69;
"F2"
$PN"F2"93;
"F3"
$PN"F3"49;
"F4"
$PN"F4"104;
"E1"
$PN"E1"2;
"E2"
$PN"E2"60;
"E3"
$PN"E3"2;
"E4"
$PN"E4"105;
"D1"
$PN"D1"68;
"D2"
$PN"D2"2;
"D3"
$PN"D3"48;
"D4"
$PN"D4"2;
"C1"
$PN"C1"106;
"C2"
$PN"C2"59;
"C3"
$PN"C3"41;
"C4"
$PN"C4"84;
"B1"
$PN"B1"2;
"B2"
$PN"B2"58;
"B3"
$PN"B3"2;
"B4"
$PN"B4"101;
"A1"
$PN"A1"67;
"A2"
$PN"A2"2;
"A3"
$PN"A3"40;
"A4"
$PN"A4"2;
%"UNIVERSAL_GND"
"1","(-775,-925)","0","logical_power","I77";
;
HDL_POWER"GND"
CDS_LIB"logical_power";
"A"1;
%"UNIVERSAL_GND"
"1","(3775,-800)","0","logical_power","I78";
;
HDL_POWER"GND"
CDS_LIB"logical_power";
"A"2;
END.
